# SCM (Grand Teton) — schematic netlist excerpt (pin names and nets, part order shuffled) for the footprints in the layout excerpt that follows; sources: Cadence DE-HDL packaged netlist, KiCad conversion of 12092022_DA0F0TMDCD0_F0T_Management_Board_D_brd_V3_OCP.brd

C102  Q_CAP  0.1UF 25V 10% X7R  pkg 0402  page 16 : A = P1V8_AUX ; B = GND
R165  Q_RES  33.2 1% CHIP  pkg 0402LF  page 12 : A = SMB_BMC_MM2_R_SCL ; B = SMB_BMC_MM2_SCL

(kicad_pcb
	(version 20260206)
	(generator "pcbnew")
	(generator_version "10.0")
	(general
		(thickness 1.6)
		(legacy_teardrops no)
	)
	(paper "A4")
	(title_block
		(title "12092022_DA0F0TMDCD0_F0T_Management_Board_D_brd_V3_OCP.brd")
		(comment 1 "Grand Teton / footprints 1094-1095 of 1440")
	)
	(layers
		(0 "F.Cu" signal "TOP")
		(4 "In1.Cu" signal "GND")
		(6 "In2.Cu" signal "IN1")
		(8 "In3.Cu" signal "GND1")
		(10 "In4.Cu" signal "IN2")
		(12 "In5.Cu" signal "VCC")
		(14 "In6.Cu" signal "VCC1")
		(16 "In7.Cu" signal "IN3")
		(18 "In8.Cu" signal "GND2")
		(20 "In9.Cu" signal "IN4")
		(22 "In10.Cu" signal "GND3")
		(2 "B.Cu" signal "BOTTOM")
		(9 "F.Adhes" user "F.Adhesive")
		(11 "B.Adhes" user "B.Adhesive")
		(13 "F.Paste" user "Package Geometry/Pastemask Top")
		(15 "B.Paste" user "Package Geometry/Pastemask Bottom")
		(5 "F.SilkS" user "Ref Des/Silkscreen Top")
		(7 "B.SilkS" user "Ref Des/Silkscreen Bottom")
		(1 "F.Mask" user "Board Geometry/Soldermask Top")
		(3 "B.Mask" user "Board Geometry/Soldermask Bottom")
		(17 "Dwgs.User" user "User.Drawings")
		(19 "Cmts.User" user "User.Comments")
		(21 "Eco1.User" user "User.Eco1")
		(23 "Eco2.User" user "User.Eco2")
		(25 "Edge.Cuts" user "Board Geometry/Outline")
		(27 "Margin" user)
		(31 "F.CrtYd" user "Package Geometry/Place Bound Top")
		(29 "B.CrtYd" user "Package Geometry/Place Bound Bottom")
		(35 "F.Fab" user "Ref Des/Assembly Top")
		(33 "B.Fab" user "Ref Des/Assembly Bottom")
	)
	(footprint ""
		(layer "B.Cu")
		(at 56.904636 -54.898544 180)
		(property "Reference" "C102"
			(at 0 0 0)
			(layer "B.SilkS")
			(hide yes)
			(effects
				(font
					(size 1.27 1.27)
				)
				(justify mirror)
			)
		)
		(property "Value" ""
			(at 0 0 0)
			(layer "B.Fab")
			(effects
				(font
					(size 1.27 1.27)
				)
				(justify mirror)
			)
		)
		(duplicate_pad_numbers_are_jumpers no)
		(fp_line
			(start 0.7874 0.4064)
			(end 0.7874 -0.4064)
			(stroke
				(width 0.1524)
				(type default)
			)
			(layer "B.SilkS")
		)
		(fp_line
			(start 0.7874 -0.4064)
			(end -0.7874 -0.4064)
			(stroke
				(width 0.1524)
				(type default)
			)
			(layer "B.SilkS")
		)
		(fp_line
			(start -0.7874 0.4064)
			(end 0.7874 0.4064)
			(stroke
				(width 0.1524)
				(type default)
			)
			(layer "B.SilkS")
		)
		(fp_line
			(start -0.7874 -0.4064)
			(end -0.7874 0.4064)
			(stroke
				(width 0.1524)
				(type default)
			)
			(layer "B.SilkS")
		)
		(fp_line
			(start 0.67945 0.3048)
			(end 0.67945 -0.305054)
			(stroke
				(width 0.1)
				(type default)
			)
			(layer "B.Fab")
		)
		(fp_line
			(start 0.67945 -0.305054)
			(end 0.12065 -0.305054)
			(stroke
				(width 0.1)
				(type default)
			)
			(layer "B.Fab")
		)
		(fp_line
			(start 0.12065 0.3048)
			(end 0.67945 0.3048)
			(stroke
				(width 0.1)
				(type default)
			)
			(layer "B.Fab")
		)
		(fp_line
			(start 0.12065 0.2794)
			(end 0.12065 0.3048)
			(stroke
				(width 0.1)
				(type default)
			)
			(layer "B.Fab")
		)
		(fp_line
			(start 0.12065 -0.2794)
			(end -0.12065 -0.2794)
			(stroke
				(width 0.1)
				(type default)
			)
			(layer "B.Fab")
		)
		(fp_line
			(start 0.12065 -0.305054)
			(end 0.12065 -0.2794)
			(stroke
				(width 0.1)
				(type default)
			)
			(layer "B.Fab")
		)
		(fp_line
			(start -0.120396 0.3048)
			(end -0.120396 0.2794)
			(stroke
				(width 0.1)
				(type default)
			)
			(layer "B.Fab")
		)
		(fp_line
			(start -0.120396 0.2794)
			(end 0.12065 0.2794)
			(stroke
				(width 0.1)
				(type default)
			)
			(layer "B.Fab")
		)
		(fp_line
			(start -0.12065 -0.2794)
			(end -0.12065 -0.3048)
			(stroke
				(width 0.1)
				(type default)
			)
			(layer "B.Fab")
		)
		(fp_line
			(start -0.12065 -0.3048)
			(end -0.67945 -0.3048)
			(stroke
				(width 0.1)
				(type default)
			)
			(layer "B.Fab")
		)
		(fp_line
			(start -0.67945 0.3048)
			(end -0.120396 0.3048)
			(stroke
				(width 0.1)
				(type default)
			)
			(layer "B.Fab")
		)
		(fp_line
			(start -0.67945 -0.3048)
			(end -0.67945 0.3048)
			(stroke
				(width 0.1)
				(type default)
			)
			(layer "B.Fab")
		)
		(pad "1" smd circle
			(at 0.40005 0)
			(size 0 0)
			(layers "B.Cu" "B.Mask" "B.Paste")
			(net "P1V8_AUX")
		)
		(pad "2" smd circle
			(at -0.40005 0)
			(size 0 0)
			(layers "B.Cu" "B.Mask" "B.Paste")
			(net "GND")
		)
	)
	(footprint ""
		(layer "B.Cu")
		(at 42.346118 -34.637726 90)
		(property "Reference" "R165"
			(at 0 0 90)
			(layer "B.SilkS")
			(hide yes)
			(effects
				(font
					(size 1.27 1.27)
				)
				(justify mirror)
			)
		)
		(property "Value" ""
			(at 0 0 90)
			(layer "B.Fab")
			(effects
				(font
					(size 1.27 1.27)
				)
				(justify mirror)
			)
		)
		(duplicate_pad_numbers_are_jumpers no)
		(fp_line
			(start 0.7874 -0.4064)
			(end -0.7874 -0.4064)
			(stroke
				(width 0.1524)
				(type default)
			)
			(layer "B.SilkS")
		)
		(fp_line
			(start -0.7874 -0.4064)
			(end -0.7874 0.4064)
			(stroke
				(width 0.1524)
				(type default)
			)
			(layer "B.SilkS")
		)
		(fp_line
			(start 0.7874 0.4064)
			(end 0.7874 -0.4064)
			(stroke
				(width 0.1524)
				(type default)
			)
			(layer "B.SilkS")
		)
		(fp_line
			(start -0.7874 0.4064)
			(end 0.7874 0.4064)
			(stroke
				(width 0.1524)
				(type default)
			)
			(layer "B.SilkS")
		)
		(fp_line
			(start 0.67945 -0.305054)
			(end 0.12065 -0.305054)
			(stroke
				(width 0.1)
				(type default)
			)
			(layer "B.Fab")
		)
		(fp_line
			(start 0.12065 -0.305054)
			(end 0.12065 -0.2794)
			(stroke
				(width 0.1)
				(type default)
			)
			(layer "B.Fab")
		)
		(fp_line
			(start -0.12065 -0.3048)
			(end -0.67945 -0.3048)
			(stroke
				(width 0.1)
				(type default)
			)
			(layer "B.Fab")
		)
		(fp_line
			(start -0.67945 -0.3048)
			(end -0.67945 0.3048)
			(stroke
				(width 0.1)
				(type default)
			)
			(layer "B.Fab")
		)
		(fp_line
			(start 0.12065 -0.2794)
			(end -0.12065 -0.2794)
			(stroke
				(width 0.1)
				(type default)
			)
			(layer "B.Fab")
		)
		(fp_line
			(start -0.12065 -0.2794)
			(end -0.12065 -0.3048)
			(stroke
				(width 0.1)
				(type default)
			)
			(layer "B.Fab")
		)
		(fp_line
			(start 0.12065 0.2794)
			(end 0.12065 0.3048)
			(stroke
				(width 0.1)
				(type default)
			)
			(layer "B.Fab")
		)
		(fp_line
			(start -0.120396 0.2794)
			(end 0.12065 0.2794)
			(stroke
				(width 0.1)
				(type default)
			)
			(layer "B.Fab")
		)
		(fp_line
			(start 0.67945 0.3048)
			(end 0.67945 -0.305054)
			(stroke
				(width 0.1)
				(type default)
			)
			(layer "B.Fab")
		)
		(fp_line
			(start 0.12065 0.3048)
			(end 0.67945 0.3048)
			(stroke
				(width 0.1)
				(type default)
			)
			(layer "B.Fab")
		)
		(fp_line
			(start -0.120396 0.3048)
			(end -0.120396 0.2794)
			(stroke
				(width 0.1)
				(type default)
			)
			(layer "B.Fab")
		)
		(fp_line
			(start -0.67945 0.3048)
			(end -0.120396 0.3048)
			(stroke
				(width 0.1)
				(type default)
			)
			(layer "B.Fab")
		)
		(pad "1" smd circle
			(at 0.40005 0 270)
			(size 0 0)
			(layers "B.Cu" "B.Mask" "B.Paste")
			(net "SMB_BMC_MM2_R_SCL")
		)
		(pad "2" smd circle
			(at -0.40005 0 270)
			(size 0 0)
			(layers "B.Cu" "B.Mask" "B.Paste")
			(net "SMB_BMC_MM2_SCL")
		)
	)
)
